(kicad_sch
	(version 20250114)
	(generator "eeschema")
	(generator_version "9.0")
	(paper "A3")
	(title_block
		(title "OCuLink to PCIe adapter")
		(date "2025-06-18")
		(rev "1.0.0")
		(company "Antmicro Ltd")
		(comment 1 "www.antmicro.com")
	)
	(bus_alias "I2C"
		(members "SDA" "SCL")
	)
	(bus_alias "PCIe"
		(members "TX3+" "TX3-" "TX2+" "TX2-" "TX1+" "TX1-" "TX0+" "TX0-" "RX3+"
			"RX3-" "RX2+" "RX2-" "RX1+" "RX1-" "RX0+" "RX0-"
		)
	)
	(bus_alias "PCIe_{REF}"
		(members "CK+" "CK-")
	)
	(text "TX/RX swapped because we need host-like \nnaming to connect to host side of PCIe x16 connector"
		(exclude_from_sim no)
		(at 174.625 191.77 0)
		(effects
			(font
				(size 1.27 1.27)
			)
			(justify left)
		)
	)
	(text "OCuLink connector"
		(exclude_from_sim no)
		(at 188.214 78.994 0)
		(effects
			(font
				(size 2 2)
				(thickness 0.4)
				(bold yes)
			)
			(justify left bottom)
		)
	)
	(junction
		(at 139.7 184.15)
		(diameter 0)
		(color 0 0 0 0)
	)
	(no_connect
		(at 246.38 210.82)
	)
	(no_connect
		(at 167.64 95.25)
	)
	(no_connect
		(at 167.64 97.79)
	)
	(no_connect
		(at 167.64 92.71)
	)
	(bus_entry
		(at 232.41 160.02)
		(size -1.27 1.27)
		(stroke
			(width 0)
			(type default)
		)
	)
	(bus_entry
		(at 232.41 149.86)
		(size -1.27 1.27)
		(stroke
			(width 0)
			(type default)
		)
	)
	(bus_entry
		(at 232.41 134.62)
		(size -1.27 1.27)
		(stroke
			(width 0)
			(type default)
		)
	)
	(bus_entry
		(at 232.41 172.72)
		(size -1.27 1.27)
		(stroke
			(width 0)
			(type default)
		)
	)
	(bus_entry
		(at 232.41 165.1)
		(size -1.27 1.27)
		(stroke
			(width 0)
			(type default)
		)
	)
	(bus_entry
		(at 231.14 110.49)
		(size 1.27 -1.27)
		(stroke
			(width 0)
			(type default)
		)
	)
	(bus_entry
		(at 232.41 137.16)
		(size -1.27 1.27)
		(stroke
			(width 0)
			(type default)
		)
	)
	(bus_entry
		(at 232.41 175.26)
		(size -1.27 1.27)
		(stroke
			(width 0)
			(type default)
		)
	)
	(bus_entry
		(at 232.41 127)
		(size -1.27 1.27)
		(stroke
			(width 0)
			(type default)
		)
	)
	(bus_entry
		(at 231.14 113.03)
		(size 1.27 -1.27)
		(stroke
			(width 0)
			(type default)
		)
	)
	(bus_entry
		(at 232.41 180.34)
		(size -1.27 1.27)
		(stroke
			(width 0)
			(type default)
		)
	)
	(bus_entry
		(at 232.41 152.4)
		(size -1.27 1.27)
		(stroke
			(width 0)
			(type default)
		)
	)
	(bus_entry
		(at 232.41 129.54)
		(size -1.27 1.27)
		(stroke
			(width 0)
			(type default)
		)
	)
	(bus_entry
		(at 232.41 144.78)
		(size -1.27 1.27)
		(stroke
			(width 0)
			(type default)
		)
	)
	(bus_entry
		(at 232.41 157.48)
		(size -1.27 1.27)
		(stroke
			(width 0)
			(type default)
		)
	)
	(bus_entry
		(at 231.14 105.41)
		(size 1.27 -1.27)
		(stroke
			(width 0)
			(type default)
		)
	)
	(bus_entry
		(at 231.14 102.87)
		(size 1.27 -1.27)
		(stroke
			(width 0)
			(type default)
		)
	)
	(bus_entry
		(at 232.41 182.88)
		(size -1.27 1.27)
		(stroke
			(width 0)
			(type default)
		)
	)
	(bus_entry
		(at 232.41 167.64)
		(size -1.27 1.27)
		(stroke
			(width 0)
			(type default)
		)
	)
	(bus_entry
		(at 232.41 142.24)
		(size -1.27 1.27)
		(stroke
			(width 0)
			(type default)
		)
	)
	(bus
		(pts
			(xy 232.41 134.62) (xy 232.41 137.16)
		)
		(stroke
			(width 0)
			(type default)
		)
	)
	(bus
		(pts
			(xy 232.41 124.46) (xy 233.68 123.19)
		)
		(stroke
			(width 0)
			(type default)
		)
	)
	(wire
		(pts
			(xy 243.84 243.84) (xy 243.84 246.38)
		)
		(stroke
			(width 0)
			(type default)
		)
	)
	(wire
		(pts
			(xy 187.96 120.65) (xy 193.04 120.65)
		)
		(stroke
			(width 0)
			(type default)
		)
	)
	(wire
		(pts
			(xy 199.39 243.84) (xy 201.93 243.84)
		)
		(stroke
			(width 0)
			(type default)
		)
	)
	(bus
		(pts
			(xy 232.41 157.48) (xy 232.41 160.02)
		)
		(stroke
			(width 0)
			(type default)
		)
	)
	(wire
		(pts
			(xy 167.64 153.67) (xy 231.14 153.67)
		)
		(stroke
			(width 0)
			(type default)
		)
	)
	(bus
		(pts
			(xy 232.41 165.1) (xy 232.41 167.64)
		)
		(stroke
			(width 0)
			(type default)
		)
	)
	(wire
		(pts
			(xy 231.14 236.22) (xy 246.38 236.22)
		)
		(stroke
			(width 0)
			(type default)
		)
	)
	(wire
		(pts
			(xy 153.67 243.84) (xy 156.21 243.84)
		)
		(stroke
			(width 0)
			(type default)
		)
	)
	(bus
		(pts
			(xy 232.41 99.06) (xy 232.41 101.6)
		)
		(stroke
			(width 0)
			(type default)
		)
	)
	(bus
		(pts
			(xy 232.41 129.54) (xy 232.41 134.62)
		)
		(stroke
			(width 0)
			(type default)
		)
	)
	(wire
		(pts
			(xy 231.14 158.75) (xy 167.64 158.75)
		)
		(stroke
			(width 0)
			(type default)
		)
	)
	(bus
		(pts
			(xy 232.41 137.16) (xy 232.41 142.24)
		)
		(stroke
			(width 0)
			(type default)
		)
	)
	(wire
		(pts
			(xy 186.69 236.22) (xy 201.93 236.22)
		)
		(stroke
			(width 0)
			(type default)
		)
	)
	(wire
		(pts
			(xy 210.82 113.03) (xy 231.14 113.03)
		)
		(stroke
			(width 0)
			(type default)
		)
	)
	(wire
		(pts
			(xy 139.7 184.15) (xy 139.7 186.69)
		)
		(stroke
			(width 0)
			(type default)
		)
	)
	(wire
		(pts
			(xy 167.64 118.11) (xy 182.88 118.11)
		)
		(stroke
			(width 0)
			(type default)
		)
	)
	(wire
		(pts
			(xy 231.14 181.61) (xy 167.64 181.61)
		)
		(stroke
			(width 0)
			(type default)
		)
	)
	(wire
		(pts
			(xy 231.14 238.76) (xy 246.38 238.76)
		)
		(stroke
			(width 0)
			(type default)
		)
	)
	(wire
		(pts
			(xy 140.97 236.22) (xy 156.21 236.22)
		)
		(stroke
			(width 0)
			(type default)
		)
	)
	(wire
		(pts
			(xy 243.84 243.84) (xy 246.38 243.84)
		)
		(stroke
			(width 0)
			(type default)
		)
	)
	(wire
		(pts
			(xy 153.67 220.98) (xy 156.21 220.98)
		)
		(stroke
			(width 0)
			(type default)
		)
	)
	(bus
		(pts
			(xy 232.41 111.76) (xy 232.41 109.22)
		)
		(stroke
			(width 0)
			(type default)
		)
	)
	(wire
		(pts
			(xy 243.84 220.98) (xy 246.38 220.98)
		)
		(stroke
			(width 0)
			(type default)
		)
	)
	(wire
		(pts
			(xy 167.64 120.65) (xy 182.88 120.65)
		)
		(stroke
			(width 0)
			(type default)
		)
	)
	(wire
		(pts
			(xy 140.97 215.9) (xy 156.21 215.9)
		)
		(stroke
			(width 0)
			(type default)
		)
	)
	(bus
		(pts
			(xy 232.41 109.22) (xy 232.41 106.68)
		)
		(stroke
			(width 0)
			(type default)
		)
	)
	(wire
		(pts
			(xy 186.69 218.44) (xy 201.93 218.44)
		)
		(stroke
			(width 0)
			(type default)
		)
	)
	(wire
		(pts
			(xy 167.64 105.41) (xy 205.74 105.41)
		)
		(stroke
			(width 0)
			(type default)
		)
	)
	(wire
		(pts
			(xy 140.97 218.44) (xy 156.21 218.44)
		)
		(stroke
			(width 0)
			(type default)
		)
	)
	(wire
		(pts
			(xy 139.7 181.61) (xy 139.7 184.15)
		)
		(stroke
			(width 0)
			(type default)
		)
	)
	(wire
		(pts
			(xy 210.82 105.41) (xy 231.14 105.41)
		)
		(stroke
			(width 0)
			(type default)
		)
	)
	(wire
		(pts
			(xy 231.14 213.36) (xy 246.38 213.36)
		)
		(stroke
			(width 0)
			(type default)
		)
	)
	(wire
		(pts
			(xy 231.14 241.3) (xy 246.38 241.3)
		)
		(stroke
			(width 0)
			(type default)
		)
	)
	(bus
		(pts
			(xy 232.41 172.72) (xy 232.41 175.26)
		)
		(stroke
			(width 0)
			(type default)
		)
	)
	(wire
		(pts
			(xy 167.64 110.49) (xy 205.74 110.49)
		)
		(stroke
			(width 0)
			(type default)
		)
	)
	(wire
		(pts
			(xy 167.64 123.19) (xy 182.88 123.19)
		)
		(stroke
			(width 0)
			(type default)
		)
	)
	(bus
		(pts
			(xy 232.41 127) (xy 232.41 129.54)
		)
		(stroke
			(width 0)
			(type default)
		)
	)
	(wire
		(pts
			(xy 140.97 213.36) (xy 156.21 213.36)
		)
		(stroke
			(width 0)
			(type default)
		)
	)
	(wire
		(pts
			(xy 231.14 161.29) (xy 167.64 161.29)
		)
		(stroke
			(width 0)
			(type default)
		)
	)
	(wire
		(pts
			(xy 231.14 184.15) (xy 167.64 184.15)
		)
		(stroke
			(width 0)
			(type default)
		)
	)
	(wire
		(pts
			(xy 186.69 238.76) (xy 201.93 238.76)
		)
		(stroke
			(width 0)
			(type default)
		)
	)
	(wire
		(pts
			(xy 186.69 233.68) (xy 201.93 233.68)
		)
		(stroke
			(width 0)
			(type default)
		)
	)
	(bus
		(pts
			(xy 232.41 144.78) (xy 232.41 149.86)
		)
		(stroke
			(width 0)
			(type default)
		)
	)
	(wire
		(pts
			(xy 186.69 241.3) (xy 201.93 241.3)
		)
		(stroke
			(width 0)
			(type default)
		)
	)
	(bus
		(pts
			(xy 233.68 105.41) (xy 236.22 105.41)
		)
		(stroke
			(width 0)
			(type default)
		)
	)
	(wire
		(pts
			(xy 140.97 233.68) (xy 156.21 233.68)
		)
		(stroke
			(width 0)
			(type default)
		)
	)
	(bus
		(pts
			(xy 232.41 142.24) (xy 232.41 144.78)
		)
		(stroke
			(width 0)
			(type default)
		)
	)
	(wire
		(pts
			(xy 186.69 215.9) (xy 201.93 215.9)
		)
		(stroke
			(width 0)
			(type default)
		)
	)
	(bus
		(pts
			(xy 232.41 124.46) (xy 232.41 127)
		)
		(stroke
			(width 0)
			(type default)
		)
	)
	(wire
		(pts
			(xy 186.69 213.36) (xy 201.93 213.36)
		)
		(stroke
			(width 0)
			(type default)
		)
	)
	(wire
		(pts
			(xy 167.64 128.27) (xy 231.14 128.27)
		)
		(stroke
			(width 0)
			(type default)
		)
	)
	(wire
		(pts
			(xy 153.67 243.84) (xy 153.67 246.38)
		)
		(stroke
			(width 0)
			(type default)
		)
	)
	(wire
		(pts
			(xy 187.96 123.19) (xy 193.04 123.19)
		)
		(stroke
			(width 0)
			(type default)
		)
	)
	(wire
		(pts
			(xy 139.7 184.15) (xy 142.24 184.15)
		)
		(stroke
			(width 0)
			(type default)
		)
	)
	(wire
		(pts
			(xy 167.64 135.89) (xy 231.14 135.89)
		)
		(stroke
			(width 0)
			(type default)
		)
	)
	(wire
		(pts
			(xy 167.64 143.51) (xy 231.14 143.51)
		)
		(stroke
			(width 0)
			(type default)
		)
	)
	(wire
		(pts
			(xy 186.69 210.82) (xy 201.93 210.82)
		)
		(stroke
			(width 0)
			(type default)
		)
	)
	(wire
		(pts
			(xy 231.14 215.9) (xy 246.38 215.9)
		)
		(stroke
			(width 0)
			(type default)
		)
	)
	(bus
		(pts
			(xy 232.41 99.06) (xy 233.68 97.79)
		)
		(stroke
			(width 0)
			(type default)
		)
	)
	(bus
		(pts
			(xy 232.41 160.02) (xy 232.41 165.1)
		)
		(stroke
			(width 0)
			(type default)
		)
	)
	(wire
		(pts
			(xy 231.14 166.37) (xy 167.64 166.37)
		)
		(stroke
			(width 0)
			(type default)
		)
	)
	(bus
		(pts
			(xy 240.03 123.19) (xy 233.68 123.19)
		)
		(stroke
			(width 0)
			(type default)
		)
	)
	(bus
		(pts
			(xy 233.68 97.79) (xy 236.22 97.79)
		)
		(stroke
			(width 0)
			(type default)
		)
	)
	(bus
		(pts
			(xy 232.41 149.86) (xy 232.41 152.4)
		)
		(stroke
			(width 0)
			(type default)
		)
	)
	(wire
		(pts
			(xy 142.24 181.61) (xy 139.7 181.61)
		)
		(stroke
			(width 0)
			(type default)
		)
	)
	(wire
		(pts
			(xy 231.14 173.99) (xy 167.64 173.99)
		)
		(stroke
			(width 0)
			(type default)
		)
	)
	(wire
		(pts
			(xy 140.97 238.76) (xy 156.21 238.76)
		)
		(stroke
			(width 0)
			(type default)
		)
	)
	(bus
		(pts
			(xy 232.41 152.4) (xy 232.41 157.48)
		)
		(stroke
			(width 0)
			(type default)
		)
	)
	(wire
		(pts
			(xy 167.64 138.43) (xy 231.14 138.43)
		)
		(stroke
			(width 0)
			(type default)
		)
	)
	(wire
		(pts
			(xy 153.67 220.98) (xy 153.67 223.52)
		)
		(stroke
			(width 0)
			(type default)
		)
	)
	(wire
		(pts
			(xy 167.64 102.87) (xy 205.74 102.87)
		)
		(stroke
			(width 0)
			(type default)
		)
	)
	(wire
		(pts
			(xy 199.39 220.98) (xy 201.93 220.98)
		)
		(stroke
			(width 0)
			(type default)
		)
	)
	(wire
		(pts
			(xy 210.82 102.87) (xy 231.14 102.87)
		)
		(stroke
			(width 0)
			(type default)
		)
	)
	(wire
		(pts
			(xy 231.14 218.44) (xy 246.38 218.44)
		)
		(stroke
			(width 0)
			(type default)
		)
	)
	(bus
		(pts
			(xy 232.41 167.64) (xy 232.41 172.72)
		)
		(stroke
			(width 0)
			(type default)
		)
	)
	(wire
		(pts
			(xy 167.64 130.81) (xy 231.14 130.81)
		)
		(stroke
			(width 0)
			(type default)
		)
	)
	(wire
		(pts
			(xy 167.64 151.13) (xy 231.14 151.13)
		)
		(stroke
			(width 0)
			(type default)
		)
	)
	(wire
		(pts
			(xy 199.39 243.84) (xy 199.39 246.38)
		)
		(stroke
			(width 0)
			(type default)
		)
	)
	(wire
		(pts
			(xy 140.97 210.82) (xy 156.21 210.82)
		)
		(stroke
			(width 0)
			(type default)
		)
	)
	(wire
		(pts
			(xy 187.96 118.11) (xy 193.04 118.11)
		)
		(stroke
			(width 0)
			(type default)
		)
	)
	(wire
		(pts
			(xy 210.82 110.49) (xy 231.14 110.49)
		)
		(stroke
			(width 0)
			(type default)
		)
	)
	(wire
		(pts
			(xy 167.64 113.03) (xy 205.74 113.03)
		)
		(stroke
			(width 0)
			(type default)
		)
	)
	(bus
		(pts
			(xy 232.41 104.14) (xy 232.41 101.6)
		)
		(stroke
			(width 0)
			(type default)
		)
	)
	(bus
		(pts
			(xy 232.41 106.68) (xy 233.68 105.41)
		)
		(stroke
			(width 0)
			(type default)
		)
	)
	(wire
		(pts
			(xy 140.97 241.3) (xy 156.21 241.3)
		)
		(stroke
			(width 0)
			(type default)
		)
	)
	(wire
		(pts
			(xy 231.14 176.53) (xy 167.64 176.53)
		)
		(stroke
			(width 0)
			(type default)
		)
	)
	(bus
		(pts
			(xy 232.41 175.26) (xy 232.41 180.34)
		)
		(stroke
			(width 0)
			(type default)
		)
	)
	(wire
		(pts
			(xy 231.14 233.68) (xy 246.38 233.68)
		)
		(stroke
			(width 0)
			(type default)
		)
	)
	(wire
		(pts
			(xy 243.84 220.98) (xy 243.84 223.52)
		)
		(stroke
			(width 0)
			(type default)
		)
	)
	(wire
		(pts
			(xy 199.39 220.98) (xy 199.39 223.52)
		)
		(stroke
			(width 0)
			(type default)
		)
	)
	(wire
		(pts
			(xy 167.64 146.05) (xy 231.14 146.05)
		)
		(stroke
			(width 0)
			(type default)
		)
	)
	(wire
		(pts
			(xy 231.14 168.91) (xy 167.64 168.91)
		)
		(stroke
			(width 0)
			(type default)
		)
	)
	(bus
		(pts
			(xy 232.41 180.34) (xy 232.41 182.88)
		)
		(stroke
			(width 0)
			(type default)
		)
	)
	(label "~{CPRSNTC}"
		(at 176.53 120.65 180)
		(effects
			(font
				(size 1.27 1.27)
			)
			(justify right bottom)
		)
	)
	(label "PCIe_{x4}.TX3+"
		(at 229.87 181.61 180)
		(effects
			(font
				(size 1.27 1.27)
			)
			(justify right bottom)
		)
	)
	(label "PCIe_{REF0}_R.CK-"
		(at 190.5 113.03 180)
		(effects
			(font
				(size 1.27 1.27)
			)
			(justify right bottom)
		)
	)
	(label "PCIe_{x4}.TX1-"
		(at 229.87 168.91 180)
		(effects
			(font
				(size 1.27 1.27)
			)
			(justify right bottom)
		)
	)
	(label "PCIe_{x4}.RX3-"
		(at 229.87 153.67 180)
		(effects
			(font
				(size 1.27 1.27)
			)
			(justify right bottom)
		)
	)
	(label "PCIe_{REF0}.CK+"
		(at 229.87 110.49 180)
		(effects
			(font
				(size 1.27 1.27)
			)
			(justify right bottom)
		)
	)
	(label "PCIe_{x4}.TX0-"
		(at 229.87 161.29 180)
		(effects
			(font
				(size 1.27 1.27)
			)
			(justify right bottom)
		)
	)
	(label "PCIe_{x4}.TX3-"
		(at 229.87 184.15 180)
		(effects
			(font
				(size 1.27 1.27)
			)
			(justify right bottom)
		)
	)
	(label "PCIe_{x4}.RX2-"
		(at 140.97 236.22 0)
		(effects
			(font
				(size 1.27 1.27)
			)
			(justify left bottom)
		)
	)
	(label "PCIe_{x4}.TX1+"
		(at 229.87 166.37 180)
		(effects
			(font
				(size 1.27 1.27)
			)
			(justify right bottom)
		)
	)
	(label "~{CPRSNTC}"
		(at 231.14 233.68 0)
		(effects
			(font
				(size 1.27 1.27)
			)
			(justify left bottom)
		)
	)
	(label "I2C0.SDA"
		(at 229.87 105.41 180)
		(effects
			(font
				(size 1.27 1.27)
			)
			(justify right bottom)
		)
	)
	(label "PCIe_{x4}.RX1+"
		(at 229.87 135.89 180)
		(effects
			(font
				(size 1.27 1.27)
			)
			(justify right bottom)
		)
	)
	(label "PCIe_{x4}.RX0+"
		(at 229.87 128.27 180)
		(effects
			(font
				(size 1.27 1.27)
			)
			(justify right bottom)
		)
	)
	(label "PCIe_{x4}.TX2+"
		(at 186.69 233.68 0)
		(effects
			(font
				(size 1.27 1.27)
			)
			(justify left bottom)
		)
	)
	(label "~{PERSTC}"
		(at 176.53 118.11 180)
		(effects
			(font
				(size 1.27 1.27)
			)
			(justify right bottom)
		)
	)
	(label "PCIe_{x4}.RX1-"
		(at 140.97 218.44 0)
		(effects
			(font
				(size 1.27 1.27)
			)
			(justify left bottom)
		)
	)
	(label "PCIe_{x4}.TX0+"
		(at 229.87 158.75 180)
		(effects
			(font
				(size 1.27 1.27)
			)
			(justify right bottom)
		)
	)
	(label "PCIe_{REF0}_R.CK+"
		(at 190.5 110.49 180)
		(effects
			(font
				(size 1.27 1.27)
			)
			(justify right bottom)
		)
	)
	(label "I2C0.SCL"
		(at 229.87 102.87 180)
		(effects
			(font
				(size 1.27 1.27)
			)
			(justify right bottom)
		)
	)
	(label "PCIe_{x4}.TX3-"
		(at 186.69 241.3 0)
		(effects
			(font
				(size 1.27 1.27)
			)
			(justify left bottom)
		)
	)
	(label "PCIe_{x4}.TX2-"
		(at 229.87 176.53 180)
		(effects
			(font
				(size 1.27 1.27)
			)
			(justify right bottom)
		)
	)
	(label "~{WAKEC}"
		(at 176.53 123.19 180)
		(effects
			(font
				(size 1.27 1.27)
			)
			(justify right bottom)
		)
	)
	(label "PCIe_{x4}.TX2-"
		(at 186.69 236.22 0)
		(effects
			(font
				(size 1.27 1.27)
			)
			(justify left bottom)
		)
	)
	(label "I2C0C_SDA"
		(at 231.14 238.76 0)
		(effects
			(font
				(size 1.27 1.27)
			)
			(justify left bottom)
		)
	)
	(label "PCIe_{x4}.RX1-"
		(at 229.87 138.43 180)
		(effects
			(font
				(size 1.27 1.27)
			)
			(justify right bottom)
		)
	)
	(label "PCIe_{REF0}_R.CK+"
		(at 231.14 215.9 0)
		(effects
			(font
				(size 1.27 1.27)
			)
			(justify left bottom)
		)
	)
	(label "PCIe_{x4}.TX0-"
		(at 186.69 213.36 0)
		(effects
			(font
				(size 1.27 1.27)
			)
			(justify left bottom)
		)
	)
	(label "PCIe_{x4}.RX0-"
		(at 140.97 213.36 0)
		(effects
			(font
				(size 1.27 1.27)
			)
			(justify left bottom)
		)
	)
	(label "PCIe_{x4}.RX1+"
		(at 140.97 215.9 0)
		(effects
			(font
				(size 1.27 1.27)
			)
			(justify left bottom)
		)
	)
	(label "PCIe_{x4}.TX0+"
		(at 186.69 210.82 0)
		(effects
			(font
				(size 1.27 1.27)
			)
			(justify left bottom)
		)
	)
	(label "~{PERSTC}"
		(at 231.14 236.22 0)
		(effects
			(font
				(size 1.27 1.27)
			)
			(justify left bottom)
		)
	)
	(label "PCIe_{x4}.RX2-"
		(at 229.87 146.05 180)
		(effects
			(font
				(size 1.27 1.27)
			)
			(justify right bottom)
		)
	)
	(label "PCIe_{x4}.TX2+"
		(at 229.87 173.99 180)
		(effects
			(font
				(size 1.27 1.27)
			)
			(justify right bottom)
		)
	)
	(label "PCIe_{x4}.RX0-"
		(at 229.87 130.81 180)
		(effects
			(font
				(size 1.27 1.27)
			)
			(justify right bottom)
		)
	)
	(label "I2C0C_SCL"
		(at 177.8 102.87 0)
		(effects
			(font
				(size 1.27 1.27)
			)
			(justify left bottom)
		)
	)
	(label "PCIe_{x4}.TX1+"
		(at 186.69 215.9 0)
		(effects
			(font
				(size 1.27 1.27)
			)
			(justify left bottom)
		)
	)
	(label "PCIe_{x4}.RX3+"
		(at 229.87 151.13 180)
		(effects
			(font
				(size 1.27 1.27)
			)
			(justify right bottom)
		)
	)
	(label "PCIe_{x4}.RX2+"
		(at 229.87 143.51 180)
		(effects
			(font
				(size 1.27 1.27)
			)
			(justify right bottom)
		)
	)
	(label "PCIe_{x4}.TX3+"
		(at 186.69 238.76 0)
		(effects
			(font
				(size 1.27 1.27)
			)
			(justify left bottom)
		)
	)
	(label "I2C0C_SDA"
		(at 177.8 105.41 0)
		(effects
			(font
				(size 1.27 1.27)
			)
			(justify left bottom)
		)
	)
	(label "PCIe_{REF0}_R.CK-"
		(at 231.14 218.44 0)
		(effects
			(font
				(size 1.27 1.27)
			)
			(justify left bottom)
		)
	)
	(label "PCIe_{x4}.RX3-"
		(at 140.97 241.3 0)
		(effects
			(font
				(size 1.27 1.27)
			)
			(justify left bottom)
		)
	)
	(label "PCIe_{x4}.RX2+"
		(at 140.97 233.68 0)
		(effects
			(font
				(size 1.27 1.27)
			)
			(justify left bottom)
		)
	)
	(label "PCIe_{REF0}.CK-"
		(at 229.87 113.03 180)
		(effects
			(font
				(size 1.27 1.27)
			)
			(justify right bottom)
		)
	)
	(label "PCIe_{x4}.RX0+"
		(at 140.97 210.82 0)
		(effects
			(font
				(size 1.27 1.27)
			)
			(justify left bottom)
		)
	)
	(label "I2C0C_SCL"
		(at 231.14 241.3 0)
		(effects
			(font
				(size 1.27 1.27)
			)
			(justify left bottom)
		)
	)
	(label "PCIe_{x4}.TX1-"
		(at 186.69 218.44 0)
		(effects
			(font
				(size 1.27 1.27)
			)
			(justify left bottom)
		)
	)
	(label "~{WAKEC}"
		(at 231.14 213.36 0)
		(effects
			(font
				(size 1.27 1.27)
			)
			(justify left bottom)
		)
	)
	(label "PCIe_{x4}.RX3+"
		(at 140.97 238.76 0)
		(effects
			(font
				(size 1.27 1.27)
			)
			(justify left bottom)
		)
	)
	(hierarchical_label "~{WAKE}"
		(shape input)
		(at 193.04 123.19 0)
		(effects
			(font
				(size 1.27 1.27)
			)
			(justify left)
		)
	)
	(hierarchical_label "PCIe_{REF0}{PCIe_{REF}}"
		(shape output)
		(at 236.22 105.41 0)
		(effects
			(font
				(size 1.27 1.27)
			)
			(justify left)
		)
	)
	(hierarchical_label "~{CPRSNT}"
		(shape input)
		(at 193.04 120.65 0)
		(effects
			(font
				(size 1.27 1.27)
			)
			(justify left)
		)
	)
	(hierarchical_label "~{PERST}"
		(shape output)
		(at 193.04 118.11 0)
		(effects
			(font
				(size 1.27 1.27)
			)
			(justify left)
		)
	)
	(hierarchical_label "PCIe_{x4}{PCIe}"
		(shape bidirectional)
		(at 240.03 123.19 0)
		(effects
			(font
				(size 1.27 1.27)
			)
			(justify left)
		)
	)
	(hierarchical_label "I2C0{I2C}"
		(shape bidirectional)
		(at 236.22 97.79 0)
		(effects
			(font
				(size 1.27 1.27)
			)
			(justify left)
		)
	)
	(rule_area
		(polyline
			(pts
				(xy 201.93 107.95) (xy 266.7 107.95) (xy 266.7 186.69) (xy 201.93 186.69)
			)
			(stroke
				(width 0)
				(type dash)
			)
			(fill
				(type none)
			)
		)
	)
	(netclass_flag ""
		(length 2.54)
		(shape round)
		(at 266.7 107.95 0)
		(effects
			(font
				(size 1.27 1.27)
				(color 0 132 0 1)
			)
			(justify left bottom)
		)
		(property "Netclass" "85Ohm-diff_PCIe"
			(at 266.7 103.632 0)
			(effects
				(font
					(size 1.27 1.27)
				)
			)
		)
		(property "Component Class" ""
			(at -105.41 -7.62 0)
			(effects
				(font
					(size 1.27 1.27)
					(italic yes)
				)
			)
		)
	)
	(symbol
		(lib_id "antmicroResistors0402:R_0R_0402")
		(at 205.74 105.41 0)
		(unit 1)
		(exclude_from_sim no)
		(in_bom yes)
		(on_board yes)
		(dnp yes)
		(property "Reference" "R2"
			(at 204.47 104.14 0)
			(effects
				(font
					(size 1.27 1.27)
					(thickness 0.15)
				)
			)
		)
		(property "Value" "R_0R_0402"
			(at 226.06 118.11 0)
			(effects
				(font
					(size 1.27 1.27)
					(thickness 0.15)
				)
				(justify left bottom)
				(hide yes)
			)
		)
		(property "Footprint" "antmicro-footprints:R_0402_1005Metric"
			(at 226.06 120.65 0)
			(effects
				(font
					(size 1.27 1.27)
					(thickness 0.15)
				)
				(justify left bottom)
				(hide yes)
			)
		)
		(property "Datasheet" "https://industrial.panasonic.com/cdbs/www-data/pdf/RDA0000/AOA0000C301.pdf"
			(at 226.06 123.19 0)
			(effects
				(font
					(size 1.27 1.27)
					(thickness 0.15)
				)
				(justify left bottom)
				(hide yes)
			)
		)
		(property "Description" "SMD Chip Resistor, Jumper, 0 ohm, 100 mW, 0402 [1005 Metric], Thick Film, General Purpose"
			(at 205.74 105.41 0)
			(effects
				(font
					(size 1.27 1.27)
				)
				(hide yes)
			)
		)
		(property "MPN" "ERJ2GE0R00X"
			(at 226.06 125.73 0)
			(effects
				(font
					(size 1.27 1.27)
					(thickness 0.15)
				)
				(justify left bottom)
				(hide yes)
			)
		)
		(property "Manufacturer" "Panasonic"
			(at 226.06 128.27 0)
			(effects
				(font
					(size 1.27 1.27)
					(thickness 0.15)
				)
				(justify left bottom)
				(hide yes)
			)
		)
		(property "License" "Apache-2.0"
			(at 226.06 130.81 0)
			(effects
				(font
					(size 1.27 1.27)
					(thickness 0.15)
				)
				(justify left bottom)
				(hide yes)
			)
		)
		(property "Author" "Antmicro"
			(at 226.06 133.35 0)
			(effects
				(font
					(size 1.27 1.27)
					(thickness 0.15)
				)
				(justify left bottom)
				(hide yes)
			)
		)
		(property "Val" "0R"
			(at 212.725 104.14 0)
			(effects
				(font
					(size 1.27 1.27)
					(thickness 0.15)
				)
			)
		)
		(property "Tolerance" "~"
			(at 226.06 115.57 0)
			(effects
				(font
					(size 1.27 1.27)
				)
				(justify left bottom)
				(hide yes)
			)
		)
		(property "Current" "1A"
			(at 226.06 135.89 0)
			(effects
				(font
					(size 1.27 1.27)
					(thickness 0.15)
				)
				(justify left bottom)
				(hide yes)
			)
		)
		(pin "1"
		)
		(pin "2"
		)
		(instances
			(project "oculink-to-pcie-adapter"
				(path ""
					(reference "R2")
					(unit 1)
				)
			)
		)
	)
	(symbol
		(lib_id "antmicropower:GND")
		(at 243.84 246.38 0)
		(mirror y)
		(unit 1)
		(exclude_from_sim no)
		(in_bom yes)
		(on_board yes)
		(dnp no)
		(property "Reference" "#PWR097"
			(at 234.95 248.92 0)
			(effects
				(font
					(size 1.27 1.27)
					(thickness 0.15)
				)
				(justify left bottom)
				(hide yes)
			)
		)
		(property "Value" "GND"
			(at 243.84 250.19 0)
			(effects
				(font
					(size 1.27 1.27)
					(thickness 0.15)
				)
			)
		)
		(property "Footprint" ""
			(at 234.95 254 0)
			(effects
				(font
					(size 1.27 1.27)
					(thickness 0.15)
				)
				(justify left bottom)
				(hide yes)
			)
		)
		(property "Datasheet" ""
			(at 234.95 259.08 0)
			(effects
				(font
					(size 1.27 1.27)
					(thickness 0.15)
				)
				(justify left bottom)
				(hide yes)
			)
		)
		(property "Description" ""
			(at 243.84 246.38 0)
			(effects
				(font
					(size 1.27 1.27)
				)
				(hide yes)
			)
		)
		(property "Author" "Antmicro"
			(at 234.95 254 0)
			(effects
				(font
					(size 1.27 1.27)
					(thickness 0.15)
				)
				(justify left bottom)
				(hide yes)
			)
		)
		(property "License" "Apache-2.0"
			(at 234.95 256.54 0)
			(effects
				(font
					(size 1.27 1.27)
					(thickness 0.15)
				)
				(justify left bottom)
				(hide yes)
			)
		)
		(pin "1"
		)
		(instances
			(project "oculink-to-pcie-adapter"
				(path ""
					(reference "#PWR097")
					(unit 1)
				)
			)
		)
	)
	(symbol
		(lib_id "antmicroTVSDiodes:ESD204DQAR")
		(at 201.93 233.68 0)
		(unit 1)
		(exclude_from_sim no)
		(in_bom yes)
		(on_board yes)
		(dnp no)
		(fields_autoplaced yes)
		(property "Reference" "D13"
			(at 212.09 237.49 0)
			(effects
				(font
					(size 1.27 1.27)
					(thickness 0.15)
				)
				(justify left)
			)
		)
		(property "Value" "ESD204DQAR"
			(at 226.06 238.76 0)
			(effects
				(font
					(size 1.27 1.27)
					(thickness 0.15)
				)
				(justify left bottom)
				(hide yes)
			)
		)
		(property "Footprint" "antmicro-footprints:USON-10_2.5x1mm_P0.5mm"
			(at 226.06 241.3 0)
			(effects
				(font
					(size 1.27 1.27)
					(thickness 0.15)
				)
				(justify left bottom)
				(hide yes)
			)
		)
		(property "Datasheet" "https://www.ti.com/lit/ds/symlink/esd204.pdf?ts=1706004844383&ref_url=https%253A%252F%252Fwww.ti.com%252Finterface%252Fdiodes%252Fesd-protection-diodes%252Fproducts.html"
			(at 226.06 243.84 0)
			(effects
				(font
					(size 1.27 1.27)
					(thickness 0.15)
				)
				(justify left bottom)
				(hide yes)
			)
		)
		(property "Description" "TVS diode array, 30 kV, USON-10, 3.6 V, 0.55 pF"
			(at 226.06 254 0)
			(effects
				(font
					(size 1.27 1.27)
				)
				(justify left bottom)
				(hide yes)
			)
		)
		(property "MPN" "ESD204DQAR"
			(at 212.09 240.03 0)
			(effects
				(font
					(size 1.27 1.27)
					(thickness 0.15)
				)
				(justify left)
			)
		)
		(property "Manufacturer" "Texas Instruments"
			(at 226.06 246.38 0)
			(effects
				(font
					(size 1.27 1.27)
					(thickness 0.15)
				)
				(justify left bottom)
				(hide yes)
			)
		)
		(property "Author" "Antmicro"
			(at 226.06 248.92 0)
			(effects
				(font
					(size 1.27 1.27)
					(thickness 0.15)
				)
				(justify left bottom)
				(hide yes)
			)
		)
		(property "License" "Apache-2.0"
			(at 226.06 251.46 0)
			(effects
				(font
					(size 1.27 1.27)
					(thickness 0.15)
				)
				(justify left bottom)
				(hide yes)
			)
		)
		(pin "7"
		)
		(pin "5"
		)
		(pin "8"
		)
		(pin "1"
		)
		(pin "6"
		)
		(pin "3"
		)
		(pin "10"
		)
		(pin "2"
		)
		(pin "4"
		)
		(pin "9"
		)
		(instances
			(project "oculink-to-pcie-adapter"
				(path ""
					(reference "D13")
					(unit 1)
				)
			)
		)
	)
	(symbol
		(lib_id "antmicropower:GND")
		(at 199.39 246.38 0)
		(mirror y)
		(unit 1)
		(exclude_from_sim no)
		(in_bom yes)
		(on_board yes)
		(dnp no)
		(property "Reference" "#PWR096"
			(at 190.5 248.92 0)
			(effects
				(font
					(size 1.27 1.27)
					(thickness 0.15)
				)
				(justify left bottom)
				(hide yes)
			)
		)
		(property "Value" "GND"
			(at 199.39 250.19 0)
			(effects
				(font
					(size 1.27 1.27)
					(thickness 0.15)
				)
			)
		)
		(property "Footprint" ""
			(at 190.5 254 0)
			(effects
				(font
					(size 1.27 1.27)
					(thickness 0.15)
				)
				(justify left bottom)
				(hide yes)
			)
		)
		(property "Datasheet" ""
			(at 190.5 259.08 0)
			(effects
				(font
					(size 1.27 1.27)
					(thickness 0.15)
				)
				(justify left bottom)
				(hide yes)
			)
		)
		(property "Description" ""
			(at 199.39 246.38 0)
			(effects
				(font
					(size 1.27 1.27)
				)
				(hide yes)
			)
		)
		(property "Author" "Antmicro"
			(at 190.5 254 0)
			(effects
				(font
					(size 1.27 1.27)
					(thickness 0.15)
				)
				(justify left bottom)
				(hide yes)
			)
		)
		(property "License" "Apache-2.0"
			(at 190.5 256.54 0)
			(effects
				(font
					(size 1.27 1.27)
					(thickness 0.15)
				)
				(justify left bottom)
				(hide yes)
			)
		)
		(pin "1"
		)
		(instances
			(project "oculink-to-pcie-adapter"
				(path ""
					(reference "#PWR096")
					(unit 1)
				)
			)
		)
	)
	(symbol
		(lib_id "antmicroTVSDiodes:ESD204DQAR")
		(at 156.21 210.82 0)
		(unit 1)
		(exclude_from_sim no)
		(in_bom yes)
		(on_board yes)
		(dnp no)
		(fields_autoplaced yes)
		(property "Reference" "D5"
			(at 166.37 214.63 0)
			(effects
				(font
					(size 1.27 1.27)
					(thickness 0.15)
				)
				(justify left)
			)
		)
		(property "Value" "ESD204DQAR"
			(at 180.34 215.9 0)
			(effects
				(font
					(size 1.27 1.27)
					(thickness 0.15)
				)
				(justify left bottom)
				(hide yes)
			)
		)
		(property "Footprint" "antmicro-footprints:USON-10_2.5x1mm_P0.5mm"
			(at 180.34 218.44 0)
			(effects
				(font
					(size 1.27 1.27)
					(thickness 0.15)
				)
				(justify left bottom)
				(hide yes)
			)
		)
		(property "Datasheet" "https://www.ti.com/lit/ds/symlink/esd204.pdf?ts=1706004844383&ref_url=https%253A%252F%252Fwww.ti.com%252Finterface%252Fdiodes%252Fesd-protection-diodes%252Fproducts.html"
			(at 180.34 220.98 0)
			(effects
				(font
					(size 1.27 1.27)
					(thickness 0.15)
				)
				(justify left bottom)
				(hide yes)
			)
		)
		(property "Description" "TVS diode array, 30 kV, USON-10, 3.6 V, 0.55 pF"
			(at 180.34 231.14 0)
			(effects
				(font
					(size 1.27 1.27)
				)
				(justify left bottom)
				(hide yes)
			)
		)
		(property "MPN" "ESD204DQAR"
			(at 166.37 217.17 0)
			(effects
				(font
					(size 1.27 1.27)
					(thickness 0.15)
				)
				(justify left)
			)
		)
		(property "Manufacturer" "Texas Instruments"
			(at 180.34 223.52 0)
			(effects
				(font
					(size 1.27 1.27)
					(thickness 0.15)
				)
				(justify left bottom)
				(hide yes)
			)
		)
		(property "Author" "Antmicro"
			(at 180.34 226.06 0)
			(effects
				(font
					(size 1.27 1.27)
					(thickness 0.15)
				)
				(justify left bottom)
				(hide yes)
			)
		)
		(property "License" "Apache-2.0"
			(at 180.34 228.6 0)
			(effects
				(font
					(size 1.27 1.27)
					(thickness 0.15)
				)
				(justify left bottom)
				(hide yes)
			)
		)
		(pin "7"
		)
		(pin "5"
		)
		(pin "8"
		)
		(pin "1"
		)
		(pin "6"
		)
		(pin "3"
		)
		(pin "10"
		)
		(pin "2"
		)
		(pin "4"
		)
		(pin "9"
		)
		(instances
			(project ""
				(path ""
					(reference "D5")
					(unit 1)
				)
			)
		)
	)
	(symbol
		(lib_id "antmicropower:GND")
		(at 199.39 223.52 0)
		(mirror y)
		(unit 1)
		(exclude_from_sim no)
		(in_bom yes)
		(on_board yes)
		(dnp no)
		(property "Reference" "#PWR095"
			(at 190.5 226.06 0)
			(effects
				(font
					(size 1.27 1.27)
					(thickness 0.15)
				)
				(justify left bottom)
				(hide yes)
			)
		)
		(property "Value" "GND"
			(at 199.39 227.33 0)
			(effects
				(font
					(size 1.27 1.27)
					(thickness 0.15)
				)
			)
		)
		(property "Footprint" ""
			(at 190.5 231.14 0)
			(effects
				(font
					(size 1.27 1.27)
					(thickness 0.15)
				)
				(justify left bottom)
				(hide yes)
			)
		)
		(property "Datasheet" ""
			(at 190.5 236.22 0)
			(effects
				(font
					(size 1.27 1.27)
					(thickness 0.15)
				)
				(justify left bottom)
				(hide yes)
			)
		)
		(property "Description" ""
			(at 199.39 223.52 0)
			(effects
				(font
					(size 1.27 1.27)
				)
				(hide yes)
			)
		)
		(property "Author" "Antmicro"
			(at 190.5 231.14 0)
			(effects
				(font
					(size 1.27 1.27)
					(thickness 0.15)
				)
				(justify left bottom)
				(hide yes)
			)
		)
		(property "License" "Apache-2.0"
			(at 190.5 233.68 0)
			(effects
				(font
					(size 1.27 1.27)
					(thickness 0.15)
				)
				(justify left bottom)
				(hide yes)
			)
		)
		(pin "1"
		)
		(instances
			(project "oculink-to-pcie-adapter"
				(path ""
					(reference "#PWR095")
					(unit 1)
				)
			)
		)
	)
	(symbol
		(lib_id "antmicroTVSDiodes:ESD204DQAR")
		(at 156.21 233.68 0)
		(unit 1)
		(exclude_from_sim no)
		(in_bom yes)
		(on_board yes)
		(dnp no)
		(fields_autoplaced yes)
		(property "Reference" "D11"
			(at 166.37 237.49 0)
			(effects
				(font
					(size 1.27 1.27)
					(thickness 0.15)
				)
				(justify left)
			)
		)
		(property "Value" "ESD204DQAR"
			(at 180.34 238.76 0)
			(effects
				(font
					(size 1.27 1.27)
					(thickness 0.15)
				)
				(justify left bottom)
				(hide yes)
			)
		)
		(property "Footprint" "antmicro-footprints:USON-10_2.5x1mm_P0.5mm"
			(at 180.34 241.3 0)
			(effects
				(font
					(size 1.27 1.27)
					(thickness 0.15)
				)
				(justify left bottom)
				(hide yes)
			)
		)
		(property "Datasheet" "https://www.ti.com/lit/ds/symlink/esd204.pdf?ts=1706004844383&ref_url=https%253A%252F%252Fwww.ti.com%252Finterface%252Fdiodes%252Fesd-protection-diodes%252Fproducts.html"
			(at 180.34 243.84 0)
			(effects
				(font
					(size 1.27 1.27)
					(thickness 0.15)
				)
				(justify left bottom)
				(hide yes)
			)
		)
		(property "Description" "TVS diode array, 30 kV, USON-10, 3.6 V, 0.55 pF"
			(at 180.34 254 0)
			(effects
				(font
					(size 1.27 1.27)
				)
				(justify left bottom)
				(hide yes)
			)
		)
		(property "MPN" "ESD204DQAR"
			(at 166.37 240.03 0)
			(effects
				(font
					(size 1.27 1.27)
					(thickness 0.15)
				)
				(justify left)
			)
		)
		(property "Manufacturer" "Texas Instruments"
			(at 180.34 246.38 0)
			(effects
				(font
					(size 1.27 1.27)
					(thickness 0.15)
				)
				(justify left bottom)
				(hide yes)
			)
		)
		(property "Author" "Antmicro"
			(at 180.34 248.92 0)
			(effects
				(font
					(size 1.27 1.27)
					(thickness 0.15)
				)
				(justify left bottom)
				(hide yes)
			)
		)
		(property "License" "Apache-2.0"
			(at 180.34 251.46 0)
			(effects
				(font
					(size 1.27 1.27)
					(thickness 0.15)
				)
				(justify left bottom)
				(hide yes)
			)
		)
		(pin "7"
		)
		(pin "5"
		)
		(pin "8"
		)
		(pin "1"
		)
		(pin "6"
		)
		(pin "3"
		)
		(pin "10"
		)
		(pin "2"
		)
		(pin "4"
		)
		(pin "9"
		)
		(instances
			(project "oculink-to-pcie-adapter"
				(path ""
					(reference "D11")
					(unit 1)
				)
			)
		)
	)
	(symbol
		(lib_id "antmicroResistors0402:R_0R_0402")
		(at 182.88 123.19 0)
		(unit 1)
		(exclude_from_sim no)
		(in_bom yes)
		(on_board yes)
		(dnp no)
		(property "Reference" "R52"
			(at 181.102 121.92 0)
			(effects
				(font
					(size 1.27 1.27)
					(thickness 0.15)
				)
			)
		)
		(property "Value" "R_0R_0402"
			(at 203.2 135.89 0)
			(effects
				(font
					(size 1.27 1.27)
					(thickness 0.15)
				)
				(justify left bottom)
				(hide yes)
			)
		)
		(property "Footprint" "antmicro-footprints:R_0402_1005Metric"
			(at 203.2 138.43 0)
			(effects
				(font
					(size 1.27 1.27)
					(thickness 0.15)
				)
				(justify left bottom)
				(hide yes)
			)
		)
		(property "Datasheet" "https://industrial.panasonic.com/cdbs/www-data/pdf/RDA0000/AOA0000C301.pdf"
			(at 203.2 140.97 0)
			(effects
				(font
					(size 1.27 1.27)
					(thickness 0.15)
				)
				(justify left bottom)
				(hide yes)
			)
		)
		(property "Description" "SMD Chip Resistor, Jumper, 0 ohm, 100 mW, 0402 [1005 Metric], Thick Film, General Purpose"
			(at 182.88 123.19 0)
			(effects
				(font
					(size 1.27 1.27)
				)
				(hide yes)
			)
		)
		(property "MPN" "ERJ2GE0R00X"
			(at 203.2 143.51 0)
			(effects
				(font
					(size 1.27 1.27)
					(thickness 0.15)
				)
				(justify left bottom)
				(hide yes)
			)
		)
		(property "Manufacturer" "Panasonic"
			(at 203.2 146.05 0)
			(effects
				(font
					(size 1.27 1.27)
					(thickness 0.15)
				)
				(justify left bottom)
				(hide yes)
			)
		)
		(property "License" "Apache-2.0"
			(at 203.2 148.59 0)
			(effects
				(font
					(size 1.27 1.27)
					(thickness 0.15)
				)
				(justify left bottom)
				(hide yes)
			)
		)
		(property "Author" "Antmicro"
			(at 203.2 151.13 0)
			(effects
				(font
					(size 1.27 1.27)
					(thickness 0.15)
				)
				(justify left bottom)
				(hide yes)
			)
		)
		(property "Val" "0R"
			(at 188.976 121.92 0)
			(effects
				(font
					(size 1.27 1.27)
					(thickness 0.15)
				)
			)
		)
		(property "Tolerance" "~"
			(at 203.2 133.35 0)
			(effects
				(font
					(size 1.27 1.27)
				)
				(justify left bottom)
				(hide yes)
			)
		)
		(property "Current" "1A"
			(at 203.2 153.67 0)
			(effects
				(font
					(size 1.27 1.27)
					(thickness 0.15)
				)
				(justify left bottom)
				(hide yes)
			)
		)
		(pin "1"
		)
		(pin "2"
		)
		(instances
			(project "oculink-to-pcie-adapter"
				(path ""
					(reference "R52")
					(unit 1)
				)
			)
		)
	)
	(symbol
		(lib_id "antmicropower:GND")
		(at 153.67 223.52 0)
		(mirror y)
		(unit 1)
		(exclude_from_sim no)
		(in_bom yes)
		(on_board yes)
		(dnp no)
		(property "Reference" "#PWR092"
			(at 144.78 226.06 0)
			(effects
				(font
					(size 1.27 1.27)
					(thickness 0.15)
				)
				(justify left bottom)
				(hide yes)
			)
		)
		(property "Value" "GND"
			(at 153.67 227.33 0)
			(effects
				(font
					(size 1.27 1.27)
					(thickness 0.15)
				)
			)
		)
		(property "Footprint" ""
			(at 144.78 231.14 0)
			(effects
				(font
					(size 1.27 1.27)
					(thickness 0.15)
				)
				(justify left bottom)
				(hide yes)
			)
		)
		(property "Datasheet" ""
			(at 144.78 236.22 0)
			(effects
				(font
					(size 1.27 1.27)
					(thickness 0.15)
				)
				(justify left bottom)
				(hide yes)
			)
		)
		(property "Description" ""
			(at 153.67 223.52 0)
			(effects
				(font
					(size 1.27 1.27)
				)
				(hide yes)
			)
		)
		(property "Author" "Antmicro"
			(at 144.78 231.14 0)
			(effects
				(font
					(size 1.27 1.27)
					(thickness 0.15)
				)
				(justify left bottom)
				(hide yes)
			)
		)
		(property "License" "Apache-2.0"
			(at 144.78 233.68 0)
			(effects
				(font
					(size 1.27 1.27)
					(thickness 0.15)
				)
				(justify left bottom)
				(hide yes)
			)
		)
		(pin "1"
		)
		(instances
			(project "oculink-to-pcie-adapter"
				(path ""
					(reference "#PWR092")
					(unit 1)
				)
			)
		)
	)
	(symbol
		(lib_id "antmicroPciConnectors:OCuLink_x4_Amphenol_G14A421211112HR_CUSTOM_device_side")
		(at 167.64 92.71 0)
		(mirror y)
		(unit 1)
		(exclude_from_sim no)
		(in_bom yes)
		(on_board yes)
		(dnp no)
		(fields_autoplaced yes)
		(property "Reference" "J1"
			(at 154.94 85.09 0)
			(effects
				(font
					(size 1.27 1.27)
					(thickness 0.15)
				)
			)
		)
		(property "Value" "OCuLink_x4_Amphenol_G14A421211112HR_CUSTOM_device_side"
			(at 128.27 105.41 0)
			(effects
				(font
					(size 1.27 1.27)
					(thickness 0.15)
				)
				(justify left bottom)
				(hide yes)
			)
		)
		(property "Footprint" "antmicro-footprints:Amphenol_G14A421211112HR"
			(at 128.27 107.95 0)
			(effects
				(font
					(size 1.27 1.27)
					(thickness 0.15)
				)
				(justify left bottom)
				(hide yes)
			)
		)
		(property "Datasheet" "https://cdn.amphenol-cs.com/media/wysiwyg/files/drawing/g14a421x1bxxxhr.pdf"
			(at 128.27 110.49 0)
			(effects
				(font
					(size 1.27 1.27)
					(thickness 0.15)
				)
				(justify left bottom)
				(hide yes)
			)
		)
		(property "Description" "I/O Connectors OCulink, Receptacle, 0.5mm pitch, 4X, R/A SMT with shell leg SMT type, 30U\" gold plating, LCP, black, T&R packing"
			(at 167.64 92.71 0)
			(effects
				(font
					(size 1.27 1.27)
				)
				(hide yes)
			)
		)
		(property "Manufacturer" "Amphenol"
			(at 128.27 102.87 0)
			(effects
				(font
					(size 1.27 1.27)
					(thickness 0.15)
				)
				(justify left bottom)
				(hide yes)
			)
		)
		(property "MPN" "G14A421211112HR"
			(at 154.94 87.63 0)
			(effects
				(font
					(size 1.27 1.27)
					(thickness 0.15)
				)
			)
		)
		(property "Author" "Antmicro"
			(at 128.27 113.03 0)
			(effects
				(font
					(size 1.27 1.27)
					(thickness 0.15)
				)
				(justify left bottom)
				(hide yes)
			)
		)
		(property "License" "Apache-2.0"
			(at 128.27 115.57 0)
			(effects
				(font
					(size 1.27 1.27)
					(thickness 0.15)
				)
				(justify left bottom)
				(hide yes)
			)
		)
		(pin "B7"
		)
		(pin "B9"
		)
		(pin "B5"
		)
		(pin "A13"
		)
		(pin "B4"
		)
		(pin "A16"
		)
		(pin "A10"
		)
		(pin "B12"
		)
		(pin "A6"
		)
		(pin "A2"
		)
		(pin "A9"
		)
		(pin "A7"
		)
		(pin "B13"
		)
		(pin "A1"
		)
		(pin "A17"
		)
		(pin "A4"
		)
		(pin "SH"
		)
		(pin "B11"
		)
		(pin "B21"
		)
		(pin "B2"
		)
		(pin "A3"
		)
		(pin "A15"
		)
		(pin "A14"
		)
		(pin "B14"
		)
		(pin "A21"
		)
		(pin "B1"
		)
		(pin "B18"
		)
		(pin "A11"
		)
		(pin "A5"
		)
		(pin "B3"
		)
		(pin "B8"
		)
		(pin "A20"
		)
		(pin "B19"
		)
		(pin "B10"
		)
		(pin "B15"
		)
		(pin "A8"
		)
		(pin "B20"
		)
		(pin "A12"
		)
		(pin "B16"
		)
		(pin "B6"
		)
		(pin "A18"
		)
		(pin "A19"
		)
		(pin "B17"
		)
		(instances
			(project ""
				(path ""
					(reference "J1")
					(unit 1)
				)
			)
		)
	)
	(symbol
		(lib_id "antmicropower:GND")
		(at 139.7 186.69 0)
		(mirror y)
		(unit 1)
		(exclude_from_sim no)
		(in_bom yes)
		(on_board yes)
		(dnp no)
		(property "Reference" "#PWR02"
			(at 130.81 189.23 0)
			(effects
				(font
					(size 1.27 1.27)
					(thickness 0.15)
				)
				(justify left bottom)
				(hide yes)
			)
		)
		(property "Value" "GND"
			(at 139.7 190.5 0)
			(effects
				(font
					(size 1.27 1.27)
					(thickness 0.15)
				)
			)
		)
		(property "Footprint" ""
			(at 130.81 194.31 0)
			(effects
				(font
					(size 1.27 1.27)
					(thickness 0.15)
				)
				(justify left bottom)
				(hide yes)
			)
		)
		(property "Datasheet" ""
			(at 130.81 199.39 0)
			(effects
				(font
					(size 1.27 1.27)
					(thickness 0.15)
				)
				(justify left bottom)
				(hide yes)
			)
		)
		(property "Description" ""
			(at 139.7 186.69 0)
			(effects
				(font
					(size 1.27 1.27)
				)
				(hide yes)
			)
		)
		(property "Author" "Antmicro"
			(at 130.81 194.31 0)
			(effects
				(font
					(size 1.27 1.27)
					(thickness 0.15)
				)
				(justify left bottom)
				(hide yes)
			)
		)
		(property "License" "Apache-2.0"
			(at 130.81 196.85 0)
			(effects
				(font
					(size 1.27 1.27)
					(thickness 0.15)
				)
				(justify left bottom)
				(hide yes)
			)
		)
		(pin "1"
		)
		(instances
			(project "oculink-to-pcie-adapter"
				(path ""
					(reference "#PWR02")
					(unit 1)
				)
			)
		)
	)
	(symbol
		(lib_id "antmicropower:GND")
		(at 153.67 246.38 0)
		(mirror y)
		(unit 1)
		(exclude_from_sim no)
		(in_bom yes)
		(on_board yes)
		(dnp no)
		(property "Reference" "#PWR093"
			(at 144.78 248.92 0)
			(effects
				(font
					(size 1.27 1.27)
					(thickness 0.15)
				)
				(justify left bottom)
				(hide yes)
			)
		)
		(property "Value" "GND"
			(at 153.67 250.19 0)
			(effects
				(font
					(size 1.27 1.27)
					(thickness 0.15)
				)
			)
		)
		(property "Footprint" ""
			(at 144.78 254 0)
			(effects
				(font
					(size 1.27 1.27)
					(thickness 0.15)
				)
				(justify left bottom)
				(hide yes)
			)
		)
		(property "Datasheet" ""
			(at 144.78 259.08 0)
			(effects
				(font
					(size 1.27 1.27)
					(thickness 0.15)
				)
				(justify left bottom)
				(hide yes)
			)
		)
		(property "Description" ""
			(at 153.67 246.38 0)
			(effects
				(font
					(size 1.27 1.27)
				)
				(hide yes)
			)
		)
		(property "Author" "Antmicro"
			(at 144.78 254 0)
			(effects
				(font
					(size 1.27 1.27)
					(thickness 0.15)
				)
				(justify left bottom)
				(hide yes)
			)
		)
		(property "License" "Apache-2.0"
			(at 144.78 256.54 0)
			(effects
				(font
					(size 1.27 1.27)
					(thickness 0.15)
				)
				(justify left bottom)
				(hide yes)
			)
		)
		(pin "1"
		)
		(instances
			(project "oculink-to-pcie-adapter"
				(path ""
					(reference "#PWR093")
					(unit 1)
				)
			)
		)
	)
	(symbol
		(lib_id "antmicroTVSDiodes:ESD204DQAR")
		(at 246.38 210.82 0)
		(unit 1)
		(exclude_from_sim no)
		(in_bom yes)
		(on_board yes)
		(dnp no)
		(fields_autoplaced yes)
		(property "Reference" "D14"
			(at 256.54 214.63 0)
			(effects
				(font
					(size 1.27 1.27)
					(thickness 0.15)
				)
				(justify left)
			)
		)
		(property "Value" "ESD204DQAR"
			(at 270.51 215.9 0)
			(effects
				(font
					(size 1.27 1.27)
					(thickness 0.15)
				)
				(justify left bottom)
				(hide yes)
			)
		)
		(property "Footprint" "antmicro-footprints:USON-10_2.5x1mm_P0.5mm"
			(at 270.51 218.44 0)
			(effects
				(font
					(size 1.27 1.27)
					(thickness 0.15)
				)
				(justify left bottom)
				(hide yes)
			)
		)
		(property "Datasheet" "https://www.ti.com/lit/ds/symlink/esd204.pdf?ts=1706004844383&ref_url=https%253A%252F%252Fwww.ti.com%252Finterface%252Fdiodes%252Fesd-protection-diodes%252Fproducts.html"
			(at 270.51 220.98 0)
			(effects
				(font
					(size 1.27 1.27)
					(thickness 0.15)
				)
				(justify left bottom)
				(hide yes)
			)
		)
		(property "Description" "TVS diode array, 30 kV, USON-10, 3.6 V, 0.55 pF"
			(at 270.51 231.14 0)
			(effects
				(font
					(size 1.27 1.27)
				)
				(justify left bottom)
				(hide yes)
			)
		)
		(property "MPN" "ESD204DQAR"
			(at 256.54 217.17 0)
			(effects
				(font
					(size 1.27 1.27)
					(thickness 0.15)
				)
				(justify left)
			)
		)
		(property "Manufacturer" "Texas Instruments"
			(at 270.51 223.52 0)
			(effects
				(font
					(size 1.27 1.27)
					(thickness 0.15)
				)
				(justify left bottom)
				(hide yes)
			)
		)
		(property "Author" "Antmicro"
			(at 270.51 226.06 0)
			(effects
				(font
					(size 1.27 1.27)
					(thickness 0.15)
				)
				(justify left bottom)
				(hide yes)
			)
		)
		(property "License" "Apache-2.0"
			(at 270.51 228.6 0)
			(effects
				(font
					(size 1.27 1.27)
					(thickness 0.15)
				)
				(justify left bottom)
				(hide yes)
			)
		)
		(pin "7"
		)
		(pin "5"
		)
		(pin "8"
		)
		(pin "1"
		)
		(pin "6"
		)
		(pin "3"
		)
		(pin "10"
		)
		(pin "2"
		)
		(pin "4"
		)
		(pin "9"
		)
		(instances
			(project "oculink-to-pcie-adapter"
				(path ""
					(reference "D14")
					(unit 1)
				)
			)
		)
	)
	(symbol
		(lib_id "antmicroResistors0402:R_0R_0402")
		(at 205.74 102.87 0)
		(unit 1)
		(exclude_from_sim no)
		(in_bom yes)
		(on_board yes)
		(dnp yes)
		(property "Reference" "R1"
			(at 204.47 101.6 0)
			(effects
				(font
					(size 1.27 1.27)
					(thickness 0.15)
				)
			)
		)
		(property "Value" "R_0R_0402"
			(at 226.06 115.57 0)
			(effects
				(font
					(size 1.27 1.27)
					(thickness 0.15)
				)
				(justify left bottom)
				(hide yes)
			)
		)
		(property "Footprint" "antmicro-footprints:R_0402_1005Metric"
			(at 226.06 118.11 0)
			(effects
				(font
					(size 1.27 1.27)
					(thickness 0.15)
				)
				(justify left bottom)
				(hide yes)
			)
		)
		(property "Datasheet" "https://industrial.panasonic.com/cdbs/www-data/pdf/RDA0000/AOA0000C301.pdf"
			(at 226.06 120.65 0)
			(effects
				(font
					(size 1.27 1.27)
					(thickness 0.15)
				)
				(justify left bottom)
				(hide yes)
			)
		)
		(property "Description" "SMD Chip Resistor, Jumper, 0 ohm, 100 mW, 0402 [1005 Metric], Thick Film, General Purpose"
			(at 205.74 102.87 0)
			(effects
				(font
					(size 1.27 1.27)
				)
				(hide yes)
			)
		)
		(property "MPN" "ERJ2GE0R00X"
			(at 226.06 123.19 0)
			(effects
				(font
					(size 1.27 1.27)
					(thickness 0.15)
				)
				(justify left bottom)
				(hide yes)
			)
		)
		(property "Manufacturer" "Panasonic"
			(at 226.06 125.73 0)
			(effects
				(font
					(size 1.27 1.27)
					(thickness 0.15)
				)
				(justify left bottom)
				(hide yes)
			)
		)
		(property "License" "Apache-2.0"
			(at 226.06 128.27 0)
			(effects
				(font
					(size 1.27 1.27)
					(thickness 0.15)
				)
				(justify left bottom)
				(hide yes)
			)
		)
		(property "Author" "Antmicro"
			(at 226.06 130.81 0)
			(effects
				(font
					(size 1.27 1.27)
					(thickness 0.15)
				)
				(justify left bottom)
				(hide yes)
			)
		)
		(property "Val" "0R"
			(at 212.725 101.6 0)
			(effects
				(font
					(size 1.27 1.27)
					(thickness 0.15)
				)
			)
		)
		(property "Tolerance" "~"
			(at 226.06 113.03 0)
			(effects
				(font
					(size 1.27 1.27)
				)
				(justify left bottom)
				(hide yes)
			)
		)
		(property "Current" "1A"
			(at 226.06 133.35 0)
			(effects
				(font
					(size 1.27 1.27)
					(thickness 0.15)
				)
				(justify left bottom)
				(hide yes)
			)
		)
		(pin "1"
		)
		(pin "2"
		)
		(instances
			(project "oculink-to-pcie-adapter"
				(path ""
					(reference "R1")
					(unit 1)
				)
			)
		)
	)
	(symbol
		(lib_id "antmicroResistors0402:R_0R_0402")
		(at 205.74 110.49 0)
		(unit 1)
		(exclude_from_sim no)
		(in_bom yes)
		(on_board yes)
		(dnp no)
		(property "Reference" "R46"
			(at 203.962 109.22 0)
			(effects
				(font
					(size 1.27 1.27)
					(thickness 0.15)
				)
			)
		)
		(property "Value" "R_0R_0402"
			(at 226.06 123.19 0)
			(effects
				(font
					(size 1.27 1.27)
					(thickness 0.15)
				)
				(justify left bottom)
				(hide yes)
			)
		)
		(property "Footprint" "antmicro-footprints:R_0402_1005Metric"
			(at 226.06 125.73 0)
			(effects
				(font
					(size 1.27 1.27)
					(thickness 0.15)
				)
				(justify left bottom)
				(hide yes)
			)
		)
		(property "Datasheet" "https://industrial.panasonic.com/cdbs/www-data/pdf/RDA0000/AOA0000C301.pdf"
			(at 226.06 128.27 0)
			(effects
				(font
					(size 1.27 1.27)
					(thickness 0.15)
				)
				(justify left bottom)
				(hide yes)
			)
		)
		(property "Description" "SMD Chip Resistor, Jumper, 0 ohm, 100 mW, 0402 [1005 Metric], Thick Film, General Purpose"
			(at 205.74 110.49 0)
			(effects
				(font
					(size 1.27 1.27)
				)
				(hide yes)
			)
		)
		(property "MPN" "ERJ2GE0R00X"
			(at 226.06 130.81 0)
			(effects
				(font
					(size 1.27 1.27)
					(thickness 0.15)
				)
				(justify left bottom)
				(hide yes)
			)
		)
		(property "Manufacturer" "Panasonic"
			(at 226.06 133.35 0)
			(effects
				(font
					(size 1.27 1.27)
					(thickness 0.15)
				)
				(justify left bottom)
				(hide yes)
			)
		)
		(property "License" "Apache-2.0"
			(at 226.06 135.89 0)
			(effects
				(font
					(size 1.27 1.27)
					(thickness 0.15)
				)
				(justify left bottom)
				(hide yes)
			)
		)
		(property "Author" "Antmicro"
			(at 226.06 138.43 0)
			(effects
				(font
					(size 1.27 1.27)
					(thickness 0.15)
				)
				(justify left bottom)
				(hide yes)
			)
		)
		(property "Val" "0R"
			(at 211.836 109.22 0)
			(effects
				(font
					(size 1.27 1.27)
					(thickness 0.15)
				)
			)
		)
		(property "Tolerance" "~"
			(at 226.06 120.65 0)
			(effects
				(font
					(size 1.27 1.27)
				)
				(justify left bottom)
				(hide yes)
			)
		)
		(property "Current" "1A"
			(at 226.06 140.97 0)
			(effects
				(font
					(size 1.27 1.27)
					(thickness 0.15)
				)
				(justify left bottom)
				(hide yes)
			)
		)
		(pin "1"
		)
		(pin "2"
		)
		(instances
			(project "oculink-to-pcie-adapter"
				(path ""
					(reference "R46")
					(unit 1)
				)
			)
		)
	)
	(symbol
		(lib_id "antmicroResistors0402:R_0R_0402")
		(at 205.74 113.03 0)
		(unit 1)
		(exclude_from_sim no)
		(in_bom yes)
		(on_board yes)
		(dnp no)
		(property "Reference" "R47"
			(at 203.962 111.76 0)
			(effects
				(font
					(size 1.27 1.27)
					(thickness 0.15)
				)
			)
		)
		(property "Value" "R_0R_0402"
			(at 226.06 125.73 0)
			(effects
				(font
					(size 1.27 1.27)
					(thickness 0.15)
				)
				(justify left bottom)
				(hide yes)
			)
		)
		(property "Footprint" "antmicro-footprints:R_0402_1005Metric"
			(at 226.06 128.27 0)
			(effects
				(font
					(size 1.27 1.27)
					(thickness 0.15)
				)
				(justify left bottom)
				(hide yes)
			)
		)
		(property "Datasheet" "https://industrial.panasonic.com/cdbs/www-data/pdf/RDA0000/AOA0000C301.pdf"
			(at 226.06 130.81 0)
			(effects
				(font
					(size 1.27 1.27)
					(thickness 0.15)
				)
				(justify left bottom)
				(hide yes)
			)
		)
		(property "Description" "SMD Chip Resistor, Jumper, 0 ohm, 100 mW, 0402 [1005 Metric], Thick Film, General Purpose"
			(at 205.74 113.03 0)
			(effects
				(font
					(size 1.27 1.27)
				)
				(hide yes)
			)
		)
		(property "MPN" "ERJ2GE0R00X"
			(at 226.06 133.35 0)
			(effects
				(font
					(size 1.27 1.27)
					(thickness 0.15)
				)
				(justify left bottom)
				(hide yes)
			)
		)
		(property "Manufacturer" "Panasonic"
			(at 226.06 135.89 0)
			(effects
				(font
					(size 1.27 1.27)
					(thickness 0.15)
				)
				(justify left bottom)
				(hide yes)
			)
		)
		(property "License" "Apache-2.0"
			(at 226.06 138.43 0)
			(effects
				(font
					(size 1.27 1.27)
					(thickness 0.15)
				)
				(justify left bottom)
				(hide yes)
			)
		)
		(property "Author" "Antmicro"
			(at 226.06 140.97 0)
			(effects
				(font
					(size 1.27 1.27)
					(thickness 0.15)
				)
				(justify left bottom)
				(hide yes)
			)
		)
		(property "Val" "0R"
			(at 211.836 111.76 0)
			(effects
				(font
					(size 1.27 1.27)
					(thickness 0.15)
				)
			)
		)
		(property "Tolerance" "~"
			(at 226.06 123.19 0)
			(effects
				(font
					(size 1.27 1.27)
				)
				(justify left bottom)
				(hide yes)
			)
		)
		(property "Current" "1A"
			(at 226.06 143.51 0)
			(effects
				(font
					(size 1.27 1.27)
					(thickness 0.15)
				)
				(justify left bottom)
				(hide yes)
			)
		)
		(pin "1"
		)
		(pin "2"
		)
		(instances
			(project "oculink-to-pcie-adapter"
				(path ""
					(reference "R47")
					(unit 1)
				)
			)
		)
	)
	(symbol
		(lib_id "antmicroResistors0402:R_0R_0402")
		(at 182.88 120.65 0)
		(unit 1)
		(exclude_from_sim no)
		(in_bom yes)
		(on_board yes)
		(dnp no)
		(property "Reference" "R51"
			(at 181.102 119.38 0)
			(effects
				(font
					(size 1.27 1.27)
					(thickness 0.15)
				)
			)
		)
		(property "Value" "R_0R_0402"
			(at 203.2 133.35 0)
			(effects
				(font
					(size 1.27 1.27)
					(thickness 0.15)
				)
				(justify left bottom)
				(hide yes)
			)
		)
		(property "Footprint" "antmicro-footprints:R_0402_1005Metric"
			(at 203.2 135.89 0)
			(effects
				(font
					(size 1.27 1.27)
					(thickness 0.15)
				)
				(justify left bottom)
				(hide yes)
			)
		)
		(property "Datasheet" "https://industrial.panasonic.com/cdbs/www-data/pdf/RDA0000/AOA0000C301.pdf"
			(at 203.2 138.43 0)
			(effects
				(font
					(size 1.27 1.27)
					(thickness 0.15)
				)
				(justify left bottom)
				(hide yes)
			)
		)
		(property "Description" "SMD Chip Resistor, Jumper, 0 ohm, 100 mW, 0402 [1005 Metric], Thick Film, General Purpose"
			(at 182.88 120.65 0)
			(effects
				(font
					(size 1.27 1.27)
				)
				(hide yes)
			)
		)
		(property "MPN" "ERJ2GE0R00X"
			(at 203.2 140.97 0)
			(effects
				(font
					(size 1.27 1.27)
					(thickness 0.15)
				)
				(justify left bottom)
				(hide yes)
			)
		)
		(property "Manufacturer" "Panasonic"
			(at 203.2 143.51 0)
			(effects
				(font
					(size 1.27 1.27)
					(thickness 0.15)
				)
				(justify left bottom)
				(hide yes)
			)
		)
		(property "License" "Apache-2.0"
			(at 203.2 146.05 0)
			(effects
				(font
					(size 1.27 1.27)
					(thickness 0.15)
				)
				(justify left bottom)
				(hide yes)
			)
		)
		(property "Author" "Antmicro"
			(at 203.2 148.59 0)
			(effects
				(font
					(size 1.27 1.27)
					(thickness 0.15)
				)
				(justify left bottom)
				(hide yes)
			)
		)
		(property "Val" "0R"
			(at 188.976 119.38 0)
			(effects
				(font
					(size 1.27 1.27)
					(thickness 0.15)
				)
			)
		)
		(property "Tolerance" "~"
			(at 203.2 130.81 0)
			(effects
				(font
					(size 1.27 1.27)
				)
				(justify left bottom)
				(hide yes)
			)
		)
		(property "Current" "1A"
			(at 203.2 151.13 0)
			(effects
				(font
					(size 1.27 1.27)
					(thickness 0.15)
				)
				(justify left bottom)
				(hide yes)
			)
		)
		(pin "1"
		)
		(pin "2"
		)
		(instances
			(project "oculink-to-pcie-adapter"
				(path ""
					(reference "R51")
					(unit 1)
				)
			)
		)
	)
	(symbol
		(lib_id "antmicroTVSDiodes:ESD204DQAR")
		(at 201.93 210.82 0)
		(unit 1)
		(exclude_from_sim no)
		(in_bom yes)
		(on_board yes)
		(dnp no)
		(fields_autoplaced yes)
		(property "Reference" "D12"
			(at 212.09 214.63 0)
			(effects
				(font
					(size 1.27 1.27)
					(thickness 0.15)
				)
				(justify left)
			)
		)
		(property "Value" "ESD204DQAR"
			(at 226.06 215.9 0)
			(effects
				(font
					(size 1.27 1.27)
					(thickness 0.15)
				)
				(justify left bottom)
				(hide yes)
			)
		)
		(property "Footprint" "antmicro-footprints:USON-10_2.5x1mm_P0.5mm"
			(at 226.06 218.44 0)
			(effects
				(font
					(size 1.27 1.27)
					(thickness 0.15)
				)
				(justify left bottom)
				(hide yes)
			)
		)
		(property "Datasheet" "https://www.ti.com/lit/ds/symlink/esd204.pdf?ts=1706004844383&ref_url=https%253A%252F%252Fwww.ti.com%252Finterface%252Fdiodes%252Fesd-protection-diodes%252Fproducts.html"
			(at 226.06 220.98 0)
			(effects
				(font
					(size 1.27 1.27)
					(thickness 0.15)
				)
				(justify left bottom)
				(hide yes)
			)
		)
		(property "Description" "TVS diode array, 30 kV, USON-10, 3.6 V, 0.55 pF"
			(at 226.06 231.14 0)
			(effects
				(font
					(size 1.27 1.27)
				)
				(justify left bottom)
				(hide yes)
			)
		)
		(property "MPN" "ESD204DQAR"
			(at 212.09 217.17 0)
			(effects
				(font
					(size 1.27 1.27)
					(thickness 0.15)
				)
				(justify left)
			)
		)
		(property "Manufacturer" "Texas Instruments"
			(at 226.06 223.52 0)
			(effects
				(font
					(size 1.27 1.27)
					(thickness 0.15)
				)
				(justify left bottom)
				(hide yes)
			)
		)
		(property "Author" "Antmicro"
			(at 226.06 226.06 0)
			(effects
				(font
					(size 1.27 1.27)
					(thickness 0.15)
				)
				(justify left bottom)
				(hide yes)
			)
		)
		(property "License" "Apache-2.0"
			(at 226.06 228.6 0)
			(effects
				(font
					(size 1.27 1.27)
					(thickness 0.15)
				)
				(justify left bottom)
				(hide yes)
			)
		)
		(pin "7"
		)
		(pin "5"
		)
		(pin "8"
		)
		(pin "1"
		)
		(pin "6"
		)
		(pin "3"
		)
		(pin "10"
		)
		(pin "2"
		)
		(pin "4"
		)
		(pin "9"
		)
		(instances
			(project "oculink-to-pcie-adapter"
				(path ""
					(reference "D12")
					(unit 1)
				)
			)
		)
	)
	(symbol
		(lib_id "antmicroResistors0402:R_0R_0402")
		(at 182.88 118.11 0)
		(unit 1)
		(exclude_from_sim no)
		(in_bom yes)
		(on_board yes)
		(dnp no)
		(property "Reference" "R50"
			(at 181.102 116.84 0)
			(effects
				(font
					(size 1.27 1.27)
					(thickness 0.15)
				)
			)
		)
		(property "Value" "R_0R_0402"
			(at 203.2 130.81 0)
			(effects
				(font
					(size 1.27 1.27)
					(thickness 0.15)
				)
				(justify left bottom)
				(hide yes)
			)
		)
		(property "Footprint" "antmicro-footprints:R_0402_1005Metric"
			(at 203.2 133.35 0)
			(effects
				(font
					(size 1.27 1.27)
					(thickness 0.15)
				)
				(justify left bottom)
				(hide yes)
			)
		)
		(property "Datasheet" "https://industrial.panasonic.com/cdbs/www-data/pdf/RDA0000/AOA0000C301.pdf"
			(at 203.2 135.89 0)
			(effects
				(font
					(size 1.27 1.27)
					(thickness 0.15)
				)
				(justify left bottom)
				(hide yes)
			)
		)
		(property "Description" "SMD Chip Resistor, Jumper, 0 ohm, 100 mW, 0402 [1005 Metric], Thick Film, General Purpose"
			(at 182.88 118.11 0)
			(effects
				(font
					(size 1.27 1.27)
				)
				(hide yes)
			)
		)
		(property "MPN" "ERJ2GE0R00X"
			(at 203.2 138.43 0)
			(effects
				(font
					(size 1.27 1.27)
					(thickness 0.15)
				)
				(justify left bottom)
				(hide yes)
			)
		)
		(property "Manufacturer" "Panasonic"
			(at 203.2 140.97 0)
			(effects
				(font
					(size 1.27 1.27)
					(thickness 0.15)
				)
				(justify left bottom)
				(hide yes)
			)
		)
		(property "License" "Apache-2.0"
			(at 203.2 143.51 0)
			(effects
				(font
					(size 1.27 1.27)
					(thickness 0.15)
				)
				(justify left bottom)
				(hide yes)
			)
		)
		(property "Author" "Antmicro"
			(at 203.2 146.05 0)
			(effects
				(font
					(size 1.27 1.27)
					(thickness 0.15)
				)
				(justify left bottom)
				(hide yes)
			)
		)
		(property "Val" "0R"
			(at 188.976 116.84 0)
			(effects
				(font
					(size 1.27 1.27)
					(thickness 0.15)
				)
			)
		)
		(property "Tolerance" "~"
			(at 203.2 128.27 0)
			(effects
				(font
					(size 1.27 1.27)
				)
				(justify left bottom)
				(hide yes)
			)
		)
		(property "Current" "1A"
			(at 203.2 148.59 0)
			(effects
				(font
					(size 1.27 1.27)
					(thickness 0.15)
				)
				(justify left bottom)
				(hide yes)
			)
		)
		(pin "1"
		)
		(pin "2"
		)
		(instances
			(project "oculink-to-pcie-adapter"
				(path ""
					(reference "R50")
					(unit 1)
				)
			)
		)
	)
	(symbol
		(lib_id "antmicropower:GND")
		(at 243.84 223.52 0)
		(mirror y)
		(unit 1)
		(exclude_from_sim no)
		(in_bom yes)
		(on_board yes)
		(dnp no)
		(property "Reference" "#PWR094"
			(at 234.95 226.06 0)
			(effects
				(font
					(size 1.27 1.27)
					(thickness 0.15)
				)
				(justify left bottom)
				(hide yes)
			)
		)
		(property "Value" "GND"
			(at 243.84 227.33 0)
			(effects
				(font
					(size 1.27 1.27)
					(thickness 0.15)
				)
			)
		)
		(property "Footprint" ""
			(at 234.95 231.14 0)
			(effects
				(font
					(size 1.27 1.27)
					(thickness 0.15)
				)
				(justify left bottom)
				(hide yes)
			)
		)
		(property "Datasheet" ""
			(at 234.95 236.22 0)
			(effects
				(font
					(size 1.27 1.27)
					(thickness 0.15)
				)
				(justify left bottom)
				(hide yes)
			)
		)
		(property "Description" ""
			(at 243.84 223.52 0)
			(effects
				(font
					(size 1.27 1.27)
				)
				(hide yes)
			)
		)
		(property "Author" "Antmicro"
			(at 234.95 231.14 0)
			(effects
				(font
					(size 1.27 1.27)
					(thickness 0.15)
				)
				(justify left bottom)
				(hide yes)
			)
		)
		(property "License" "Apache-2.0"
			(at 234.95 233.68 0)
			(effects
				(font
					(size 1.27 1.27)
					(thickness 0.15)
				)
				(justify left bottom)
				(hide yes)
			)
		)
		(pin "1"
		)
		(instances
			(project "oculink-to-pcie-adapter"
				(path ""
					(reference "#PWR094")
					(unit 1)
				)
			)
		)
	)
	(symbol
		(lib_id "antmicroTVSDiodes:ESD204DQAR")
		(at 246.38 233.68 0)
		(unit 1)
		(exclude_from_sim no)
		(in_bom yes)
		(on_board yes)
		(dnp no)
		(fields_autoplaced yes)
		(property "Reference" "D15"
			(at 256.54 237.49 0)
			(effects
				(font
					(size 1.27 1.27)
					(thickness 0.15)
				)
				(justify left)
			)
		)
		(property "Value" "ESD204DQAR"
			(at 270.51 238.76 0)
			(effects
				(font
					(size 1.27 1.27)
					(thickness 0.15)
				)
				(justify left bottom)
				(hide yes)
			)
		)
		(property "Footprint" "antmicro-footprints:USON-10_2.5x1mm_P0.5mm"
			(at 270.51 241.3 0)
			(effects
				(font
					(size 1.27 1.27)
					(thickness 0.15)
				)
				(justify left bottom)
				(hide yes)
			)
		)
		(property "Datasheet" "https://www.ti.com/lit/ds/symlink/esd204.pdf?ts=1706004844383&ref_url=https%253A%252F%252Fwww.ti.com%252Finterface%252Fdiodes%252Fesd-protection-diodes%252Fproducts.html"
			(at 270.51 243.84 0)
			(effects
				(font
					(size 1.27 1.27)
					(thickness 0.15)
				)
				(justify left bottom)
				(hide yes)
			)
		)
		(property "Description" "TVS diode array, 30 kV, USON-10, 3.6 V, 0.55 pF"
			(at 270.51 254 0)
			(effects
				(font
					(size 1.27 1.27)
				)
				(justify left bottom)
				(hide yes)
			)
		)
		(property "MPN" "ESD204DQAR"
			(at 256.54 240.03 0)
			(effects
				(font
					(size 1.27 1.27)
					(thickness 0.15)
				)
				(justify left)
			)
		)
		(property "Manufacturer" "Texas Instruments"
			(at 270.51 246.38 0)
			(effects
				(font
					(size 1.27 1.27)
					(thickness 0.15)
				)
				(justify left bottom)
				(hide yes)
			)
		)
		(property "Author" "Antmicro"
			(at 270.51 248.92 0)
			(effects
				(font
					(size 1.27 1.27)
					(thickness 0.15)
				)
				(justify left bottom)
				(hide yes)
			)
		)
		(property "License" "Apache-2.0"
			(at 270.51 251.46 0)
			(effects
				(font
					(size 1.27 1.27)
					(thickness 0.15)
				)
				(justify left bottom)
				(hide yes)
			)
		)
		(pin "7"
		)
		(pin "5"
		)
		(pin "8"
		)
		(pin "1"
		)
		(pin "6"
		)
		(pin "3"
		)
		(pin "10"
		)
		(pin "2"
		)
		(pin "4"
		)
		(pin "9"
		)
		(instances
			(project "oculink-to-pcie-adapter"
				(path ""
					(reference "D15")
					(unit 1)
				)
			)
		)
	)
)
